FILE_TYPE=LIBRARY_PARTS;
primitive 'SCONN120_A28699018','SCONN120_A28699018_SM';
  pin
    'IO1':
      PIN_NUMBER='(1)';
      BIDIRECTIONAL='TRUE';
      INPUT_LOAD='(-0.01,0.01)';
      OUTPUT_LOAD='(1.0,-1.0)';
    'IO10':
      PIN_NUMBER='(10)';
      BIDIRECTIONAL='TRUE';
      INPUT_LOAD='(-0.01,0.01)';
      OUTPUT_LOAD='(1.0,-1.0)';
    'IO100':
      PIN_NUMBER='(100)';
      BIDIRECTIONAL='TRUE';
      INPUT_LOAD='(-0.01,0.01)';
      OUTPUT_LOAD='(1.0,-1.0)';
    'IO101':
      PIN_NUMBER='(101)';
      BIDIRECTIONAL='TRUE';
      INPUT_LOAD='(-0.01,0.01)';
      OUTPUT_LOAD='(1.0,-1.0)';
    'IO102':
      PIN_NUMBER='(102)';
      BIDIRECTIONAL='TRUE';
      INPUT_LOAD='(-0.01,0.01)';
      OUTPUT_LOAD='(1.0,-1.0)';
    'IO103':
      PIN_NUMBER='(103)';
      BIDIRECTIONAL='TRUE';
      INPUT_LOAD='(-0.01,0.01)';
      OUTPUT_LOAD='(1.0,-1.0)';
    'IO104':
      PIN_NUMBER='(104)';
      BIDIRECTIONAL='TRUE';
      INPUT_LOAD='(-0.01,0.01)';
      OUTPUT_LOAD='(1.0,-1.0)';
    'IO105':
      PIN_NUMBER='(105)';
      BIDIRECTIONAL='TRUE';
      INPUT_LOAD='(-0.01,0.01)';
      OUTPUT_LOAD='(1.0,-1.0)';
    'IO106':
      PIN_NUMBER='(106)';
      BIDIRECTIONAL='TRUE';
      INPUT_LOAD='(-0.01,0.01)';
      OUTPUT_LOAD='(1.0,-1.0)';
    'IO107':
      PIN_NUMBER='(107)';
      BIDIRECTIONAL='TRUE';
      INPUT_LOAD='(-0.01,0.01)';
      OUTPUT_LOAD='(1.0,-1.0)';
    'IO108':
      PIN_NUMBER='(108)';
      BIDIRECTIONAL='TRUE';
      INPUT_LOAD='(-0.01,0.01)';
      OUTPUT_LOAD='(1.0,-1.0)';
    'IO109':
      PIN_NUMBER='(109)';
      BIDIRECTIONAL='TRUE';
      INPUT_LOAD='(-0.01,0.01)';
      OUTPUT_LOAD='(1.0,-1.0)';
    'IO11':
      PIN_NUMBER='(11)';
      BIDIRECTIONAL='TRUE';
      INPUT_LOAD='(-0.01,0.01)';
      OUTPUT_LOAD='(1.0,-1.0)';
    'IO110':
      PIN_NUMBER='(110)';
      BIDIRECTIONAL='TRUE';
      INPUT_LOAD='(-0.01,0.01)';
      OUTPUT_LOAD='(1.0,-1.0)';
    'IO111':
      PIN_NUMBER='(111)';
      BIDIRECTIONAL='TRUE';
      INPUT_LOAD='(-0.01,0.01)';
      OUTPUT_LOAD='(1.0,-1.0)';
    'IO112':
      PIN_NUMBER='(112)';
      BIDIRECTIONAL='TRUE';
      INPUT_LOAD='(-0.01,0.01)';
      OUTPUT_LOAD='(1.0,-1.0)';
    'IO113':
      PIN_NUMBER='(113)';
      BIDIRECTIONAL='TRUE';
      INPUT_LOAD='(-0.01,0.01)';
      OUTPUT_LOAD='(1.0,-1.0)';
    'IO114':
      PIN_NUMBER='(114)';
      BIDIRECTIONAL='TRUE';
      INPUT_LOAD='(-0.01,0.01)';
      OUTPUT_LOAD='(1.0,-1.0)';
    'IO115':
      PIN_NUMBER='(115)';
      BIDIRECTIONAL='TRUE';
      INPUT_LOAD='(-0.01,0.01)';
      OUTPUT_LOAD='(1.0,-1.0)';
    'IO116':
      PIN_NUMBER='(116)';
      BIDIRECTIONAL='TRUE';
      INPUT_LOAD='(-0.01,0.01)';
      OUTPUT_LOAD='(1.0,-1.0)';
    'IO117':
      PIN_NUMBER='(117)';
      BIDIRECTIONAL='TRUE';
      INPUT_LOAD='(-0.01,0.01)';
      OUTPUT_LOAD='(1.0,-1.0)';
    'IO118':
      PIN_NUMBER='(118)';
      BIDIRECTIONAL='TRUE';
      INPUT_LOAD='(-0.01,0.01)';
      OUTPUT_LOAD='(1.0,-1.0)';
    'IO119':
      PIN_NUMBER='(119)';
      BIDIRECTIONAL='TRUE';
      INPUT_LOAD='(-0.01,0.01)';
      OUTPUT_LOAD='(1.0,-1.0)';
    'IO12':
      PIN_NUMBER='(12)';
      BIDIRECTIONAL='TRUE';
      INPUT_LOAD='(-0.01,0.01)';
      OUTPUT_LOAD='(1.0,-1.0)';
    'IO120':
      PIN_NUMBER='(120)';
      BIDIRECTIONAL='TRUE';
      INPUT_LOAD='(-0.01,0.01)';
      OUTPUT_LOAD='(1.0,-1.0)';
    'IO13':
      PIN_NUMBER='(13)';
      BIDIRECTIONAL='TRUE';
      INPUT_LOAD='(-0.01,0.01)';
      OUTPUT_LOAD='(1.0,-1.0)';
    'IO14':
      PIN_NUMBER='(14)';
      BIDIRECTIONAL='TRUE';
      INPUT_LOAD='(-0.01,0.01)';
      OUTPUT_LOAD='(1.0,-1.0)';
    'IO15':
      PIN_NUMBER='(15)';
      BIDIRECTIONAL='TRUE';
      INPUT_LOAD='(-0.01,0.01)';
      OUTPUT_LOAD='(1.0,-1.0)';
    'IO16':
      PIN_NUMBER='(16)';
      BIDIRECTIONAL='TRUE';
      INPUT_LOAD='(-0.01,0.01)';
      OUTPUT_LOAD='(1.0,-1.0)';
    'IO17':
      PIN_NUMBER='(17)';
      BIDIRECTIONAL='TRUE';
      INPUT_LOAD='(-0.01,0.01)';
      OUTPUT_LOAD='(1.0,-1.0)';
    'IO18':
      PIN_NUMBER='(18)';
      BIDIRECTIONAL='TRUE';
      INPUT_LOAD='(-0.01,0.01)';
      OUTPUT_LOAD='(1.0,-1.0)';
    'IO19':
      PIN_NUMBER='(19)';
      BIDIRECTIONAL='TRUE';
      INPUT_LOAD='(-0.01,0.01)';
      OUTPUT_LOAD='(1.0,-1.0)';
    'IO2':
      PIN_NUMBER='(2)';
      BIDIRECTIONAL='TRUE';
      INPUT_LOAD='(-0.01,0.01)';
      OUTPUT_LOAD='(1.0,-1.0)';
    'IO20':
      PIN_NUMBER='(20)';
      BIDIRECTIONAL='TRUE';
      INPUT_LOAD='(-0.01,0.01)';
      OUTPUT_LOAD='(1.0,-1.0)';
    'IO21':
      PIN_NUMBER='(21)';
      BIDIRECTIONAL='TRUE';
      INPUT_LOAD='(-0.01,0.01)';
      OUTPUT_LOAD='(1.0,-1.0)';
    'IO22':
      PIN_NUMBER='(22)';
      BIDIRECTIONAL='TRUE';
      INPUT_LOAD='(-0.01,0.01)';
      OUTPUT_LOAD='(1.0,-1.0)';
    'IO23':
      PIN_NUMBER='(23)';
      BIDIRECTIONAL='TRUE';
      INPUT_LOAD='(-0.01,0.01)';
      OUTPUT_LOAD='(1.0,-1.0)';
    'IO24':
      PIN_NUMBER='(24)';
      BIDIRECTIONAL='TRUE';
      INPUT_LOAD='(-0.01,0.01)';
      OUTPUT_LOAD='(1.0,-1.0)';
    'IO25':
      PIN_NUMBER='(25)';
      BIDIRECTIONAL='TRUE';
      INPUT_LOAD='(-0.01,0.01)';
      OUTPUT_LOAD='(1.0,-1.0)';
    'IO26':
      PIN_NUMBER='(26)';
      BIDIRECTIONAL='TRUE';
      INPUT_LOAD='(-0.01,0.01)';
      OUTPUT_LOAD='(1.0,-1.0)';
    'IO27':
      PIN_NUMBER='(27)';
      BIDIRECTIONAL='TRUE';
      INPUT_LOAD='(-0.01,0.01)';
      OUTPUT_LOAD='(1.0,-1.0)';
    'IO28':
      PIN_NUMBER='(28)';
      BIDIRECTIONAL='TRUE';
      INPUT_LOAD='(-0.01,0.01)';
      OUTPUT_LOAD='(1.0,-1.0)';
    'IO29':
      PIN_NUMBER='(29)';
      BIDIRECTIONAL='TRUE';
      INPUT_LOAD='(-0.01,0.01)';
      OUTPUT_LOAD='(1.0,-1.0)';
    'IO3':
      PIN_NUMBER='(3)';
      BIDIRECTIONAL='TRUE';
      INPUT_LOAD='(-0.01,0.01)';
      OUTPUT_LOAD='(1.0,-1.0)';
    'IO30':
      PIN_NUMBER='(30)';
      BIDIRECTIONAL='TRUE';
      INPUT_LOAD='(-0.01,0.01)';
      OUTPUT_LOAD='(1.0,-1.0)';
    'IO31':
      PIN_NUMBER='(31)';
      BIDIRECTIONAL='TRUE';
      INPUT_LOAD='(-0.01,0.01)';
      OUTPUT_LOAD='(1.0,-1.0)';
    'IO32':
      PIN_NUMBER='(32)';
      BIDIRECTIONAL='TRUE';
      INPUT_LOAD='(-0.01,0.01)';
      OUTPUT_LOAD='(1.0,-1.0)';
    'IO33':
      PIN_NUMBER='(33)';
      BIDIRECTIONAL='TRUE';
      INPUT_LOAD='(-0.01,0.01)';
      OUTPUT_LOAD='(1.0,-1.0)';
    'IO34':
      PIN_NUMBER='(34)';
      BIDIRECTIONAL='TRUE';
      INPUT_LOAD='(-0.01,0.01)';
      OUTPUT_LOAD='(1.0,-1.0)';
    'IO35':
      PIN_NUMBER='(35)';
      BIDIRECTIONAL='TRUE';
      INPUT_LOAD='(-0.01,0.01)';
      OUTPUT_LOAD='(1.0,-1.0)';
    'IO36':
      PIN_NUMBER='(36)';
      BIDIRECTIONAL='TRUE';
      INPUT_LOAD='(-0.01,0.01)';
      OUTPUT_LOAD='(1.0,-1.0)';
    'IO37':
      PIN_NUMBER='(37)';
      BIDIRECTIONAL='TRUE';
      INPUT_LOAD='(-0.01,0.01)';
      OUTPUT_LOAD='(1.0,-1.0)';
    'IO38':
      PIN_NUMBER='(38)';
      BIDIRECTIONAL='TRUE';
      INPUT_LOAD='(-0.01,0.01)';
      OUTPUT_LOAD='(1.0,-1.0)';
    'IO39':
      PIN_NUMBER='(39)';
      BIDIRECTIONAL='TRUE';
      INPUT_LOAD='(-0.01,0.01)';
      OUTPUT_LOAD='(1.0,-1.0)';
    'IO4':
      PIN_NUMBER='(4)';
      BIDIRECTIONAL='TRUE';
      INPUT_LOAD='(-0.01,0.01)';
      OUTPUT_LOAD='(1.0,-1.0)';
    'IO40':
      PIN_NUMBER='(40)';
      BIDIRECTIONAL='TRUE';
      INPUT_LOAD='(-0.01,0.01)';
      OUTPUT_LOAD='(1.0,-1.0)';
    'IO41':
      PIN_NUMBER='(41)';
      BIDIRECTIONAL='TRUE';
      INPUT_LOAD='(-0.01,0.01)';
      OUTPUT_LOAD='(1.0,-1.0)';
    'IO42':
      PIN_NUMBER='(42)';
      BIDIRECTIONAL='TRUE';
      INPUT_LOAD='(-0.01,0.01)';
      OUTPUT_LOAD='(1.0,-1.0)';
    'IO43':
      PIN_NUMBER='(43)';
      BIDIRECTIONAL='TRUE';
      INPUT_LOAD='(-0.01,0.01)';
      OUTPUT_LOAD='(1.0,-1.0)';
    'IO44':
      PIN_NUMBER='(44)';
      BIDIRECTIONAL='TRUE';
      INPUT_LOAD='(-0.01,0.01)';
      OUTPUT_LOAD='(1.0,-1.0)';
    'IO45':
      PIN_NUMBER='(45)';
      BIDIRECTIONAL='TRUE';
      INPUT_LOAD='(-0.01,0.01)';
      OUTPUT_LOAD='(1.0,-1.0)';
    'IO46':
      PIN_NUMBER='(46)';
      BIDIRECTIONAL='TRUE';
      INPUT_LOAD='(-0.01,0.01)';
      OUTPUT_LOAD='(1.0,-1.0)';
    'IO47':
      PIN_NUMBER='(47)';
      BIDIRECTIONAL='TRUE';
      INPUT_LOAD='(-0.01,0.01)';
      OUTPUT_LOAD='(1.0,-1.0)';
    'IO48':
      PIN_NUMBER='(48)';
      BIDIRECTIONAL='TRUE';
      INPUT_LOAD='(-0.01,0.01)';
      OUTPUT_LOAD='(1.0,-1.0)';
    'IO49':
      PIN_NUMBER='(49)';
      BIDIRECTIONAL='TRUE';
      INPUT_LOAD='(-0.01,0.01)';
      OUTPUT_LOAD='(1.0,-1.0)';
    'IO5':
      PIN_NUMBER='(5)';
      BIDIRECTIONAL='TRUE';
      INPUT_LOAD='(-0.01,0.01)';
      OUTPUT_LOAD='(1.0,-1.0)';
    'IO50':
      PIN_NUMBER='(50)';
      BIDIRECTIONAL='TRUE';
      INPUT_LOAD='(-0.01,0.01)';
      OUTPUT_LOAD='(1.0,-1.0)';
    'IO51':
      PIN_NUMBER='(51)';
      BIDIRECTIONAL='TRUE';
      INPUT_LOAD='(-0.01,0.01)';
      OUTPUT_LOAD='(1.0,-1.0)';
    'IO52':
      PIN_NUMBER='(52)';
      BIDIRECTIONAL='TRUE';
      INPUT_LOAD='(-0.01,0.01)';
      OUTPUT_LOAD='(1.0,-1.0)';
    'IO53':
      PIN_NUMBER='(53)';
      BIDIRECTIONAL='TRUE';
      INPUT_LOAD='(-0.01,0.01)';
      OUTPUT_LOAD='(1.0,-1.0)';
    'IO54':
      PIN_NUMBER='(54)';
      BIDIRECTIONAL='TRUE';
      INPUT_LOAD='(-0.01,0.01)';
      OUTPUT_LOAD='(1.0,-1.0)';
    'IO55':
      PIN_NUMBER='(55)';
      BIDIRECTIONAL='TRUE';
      INPUT_LOAD='(-0.01,0.01)';
      OUTPUT_LOAD='(1.0,-1.0)';
    'IO56':
      PIN_NUMBER='(56)';
      BIDIRECTIONAL='TRUE';
      INPUT_LOAD='(-0.01,0.01)';
      OUTPUT_LOAD='(1.0,-1.0)';
    'IO57':
      PIN_NUMBER='(57)';
      BIDIRECTIONAL='TRUE';
      INPUT_LOAD='(-0.01,0.01)';
      OUTPUT_LOAD='(1.0,-1.0)';
    'IO58':
      PIN_NUMBER='(58)';
      BIDIRECTIONAL='TRUE';
      INPUT_LOAD='(-0.01,0.01)';
      OUTPUT_LOAD='(1.0,-1.0)';
    'IO59':
      PIN_NUMBER='(59)';
      BIDIRECTIONAL='TRUE';
      INPUT_LOAD='(-0.01,0.01)';
      OUTPUT_LOAD='(1.0,-1.0)';
    'IO6':
      PIN_NUMBER='(6)';
      BIDIRECTIONAL='TRUE';
      INPUT_LOAD='(-0.01,0.01)';
      OUTPUT_LOAD='(1.0,-1.0)';
    'IO60':
      PIN_NUMBER='(60)';
      BIDIRECTIONAL='TRUE';
      INPUT_LOAD='(-0.01,0.01)';
      OUTPUT_LOAD='(1.0,-1.0)';
    'IO61':
      PIN_NUMBER='(61)';
      BIDIRECTIONAL='TRUE';
      INPUT_LOAD='(-0.01,0.01)';
      OUTPUT_LOAD='(1.0,-1.0)';
    'IO62':
      PIN_NUMBER='(62)';
      BIDIRECTIONAL='TRUE';
      INPUT_LOAD='(-0.01,0.01)';
      OUTPUT_LOAD='(1.0,-1.0)';
    'IO63':
      PIN_NUMBER='(63)';
      BIDIRECTIONAL='TRUE';
      INPUT_LOAD='(-0.01,0.01)';
      OUTPUT_LOAD='(1.0,-1.0)';
    'IO64':
      PIN_NUMBER='(64)';
      BIDIRECTIONAL='TRUE';
      INPUT_LOAD='(-0.01,0.01)';
      OUTPUT_LOAD='(1.0,-1.0)';
    'IO65':
      PIN_NUMBER='(65)';
      BIDIRECTIONAL='TRUE';
      INPUT_LOAD='(-0.01,0.01)';
      OUTPUT_LOAD='(1.0,-1.0)';
    'IO66':
      PIN_NUMBER='(66)';
      BIDIRECTIONAL='TRUE';
      INPUT_LOAD='(-0.01,0.01)';
      OUTPUT_LOAD='(1.0,-1.0)';
    'IO67':
      PIN_NUMBER='(67)';
      BIDIRECTIONAL='TRUE';
      INPUT_LOAD='(-0.01,0.01)';
      OUTPUT_LOAD='(1.0,-1.0)';
    'IO68':
      PIN_NUMBER='(68)';
      BIDIRECTIONAL='TRUE';
      INPUT_LOAD='(-0.01,0.01)';
      OUTPUT_LOAD='(1.0,-1.0)';
    'IO69':
      PIN_NUMBER='(69)';
      BIDIRECTIONAL='TRUE';
      INPUT_LOAD='(-0.01,0.01)';
      OUTPUT_LOAD='(1.0,-1.0)';
    'IO7':
      PIN_NUMBER='(7)';
      BIDIRECTIONAL='TRUE';
      INPUT_LOAD='(-0.01,0.01)';
      OUTPUT_LOAD='(1.0,-1.0)';
    'IO70':
      PIN_NUMBER='(70)';
      BIDIRECTIONAL='TRUE';
      INPUT_LOAD='(-0.01,0.01)';
      OUTPUT_LOAD='(1.0,-1.0)';
    'IO71':
      PIN_NUMBER='(71)';
      BIDIRECTIONAL='TRUE';
      INPUT_LOAD='(-0.01,0.01)';
      OUTPUT_LOAD='(1.0,-1.0)';
    'IO72':
      PIN_NUMBER='(72)';
      BIDIRECTIONAL='TRUE';
      INPUT_LOAD='(-0.01,0.01)';
      OUTPUT_LOAD='(1.0,-1.0)';
    'IO73':
      PIN_NUMBER='(73)';
      BIDIRECTIONAL='TRUE';
      INPUT_LOAD='(-0.01,0.01)';
      OUTPUT_LOAD='(1.0,-1.0)';
    'IO74':
      PIN_NUMBER='(74)';
      BIDIRECTIONAL='TRUE';
      INPUT_LOAD='(-0.01,0.01)';
      OUTPUT_LOAD='(1.0,-1.0)';
    'IO75':
      PIN_NUMBER='(75)';
      BIDIRECTIONAL='TRUE';
      INPUT_LOAD='(-0.01,0.01)';
      OUTPUT_LOAD='(1.0,-1.0)';
    'IO76':
      PIN_NUMBER='(76)';
      BIDIRECTIONAL='TRUE';
      INPUT_LOAD='(-0.01,0.01)';
      OUTPUT_LOAD='(1.0,-1.0)';
    'IO77':
      PIN_NUMBER='(77)';
      BIDIRECTIONAL='TRUE';
      INPUT_LOAD='(-0.01,0.01)';
      OUTPUT_LOAD='(1.0,-1.0)';
    'IO78':
      PIN_NUMBER='(78)';
      BIDIRECTIONAL='TRUE';
      INPUT_LOAD='(-0.01,0.01)';
      OUTPUT_LOAD='(1.0,-1.0)';
    'IO79':
      PIN_NUMBER='(79)';
      BIDIRECTIONAL='TRUE';
      INPUT_LOAD='(-0.01,0.01)';
      OUTPUT_LOAD='(1.0,-1.0)';
    'IO8':
      PIN_NUMBER='(8)';
      BIDIRECTIONAL='TRUE';
      INPUT_LOAD='(-0.01,0.01)';
      OUTPUT_LOAD='(1.0,-1.0)';
    'IO80':
      PIN_NUMBER='(80)';
      BIDIRECTIONAL='TRUE';
      INPUT_LOAD='(-0.01,0.01)';
      OUTPUT_LOAD='(1.0,-1.0)';
    'IO81':
      PIN_NUMBER='(81)';
      BIDIRECTIONAL='TRUE';
      INPUT_LOAD='(-0.01,0.01)';
      OUTPUT_LOAD='(1.0,-1.0)';
    'IO82':
      PIN_NUMBER='(82)';
      BIDIRECTIONAL='TRUE';
      INPUT_LOAD='(-0.01,0.01)';
      OUTPUT_LOAD='(1.0,-1.0)';
    'IO83':
      PIN_NUMBER='(83)';
      BIDIRECTIONAL='TRUE';
      INPUT_LOAD='(-0.01,0.01)';
      OUTPUT_LOAD='(1.0,-1.0)';
    'IO84':
      PIN_NUMBER='(84)';
      BIDIRECTIONAL='TRUE';
      INPUT_LOAD='(-0.01,0.01)';
      OUTPUT_LOAD='(1.0,-1.0)';
    'IO85':
      PIN_NUMBER='(85)';
      BIDIRECTIONAL='TRUE';
      INPUT_LOAD='(-0.01,0.01)';
      OUTPUT_LOAD='(1.0,-1.0)';
    'IO86':
      PIN_NUMBER='(86)';
      BIDIRECTIONAL='TRUE';
      INPUT_LOAD='(-0.01,0.01)';
      OUTPUT_LOAD='(1.0,-1.0)';
    'IO87':
      PIN_NUMBER='(87)';
      BIDIRECTIONAL='TRUE';
      INPUT_LOAD='(-0.01,0.01)';
      OUTPUT_LOAD='(1.0,-1.0)';
    'IO88':
      PIN_NUMBER='(88)';
      BIDIRECTIONAL='TRUE';
      INPUT_LOAD='(-0.01,0.01)';
      OUTPUT_LOAD='(1.0,-1.0)';
    'IO89':
      PIN_NUMBER='(89)';
      BIDIRECTIONAL='TRUE';
      INPUT_LOAD='(-0.01,0.01)';
      OUTPUT_LOAD='(1.0,-1.0)';
    'IO9':
      PIN_NUMBER='(9)';
      BIDIRECTIONAL='TRUE';
      INPUT_LOAD='(-0.01,0.01)';
      OUTPUT_LOAD='(1.0,-1.0)';
    'IO90':
      PIN_NUMBER='(90)';
      BIDIRECTIONAL='TRUE';
      INPUT_LOAD='(-0.01,0.01)';
      OUTPUT_LOAD='(1.0,-1.0)';
    'IO91':
      PIN_NUMBER='(91)';
      BIDIRECTIONAL='TRUE';
      INPUT_LOAD='(-0.01,0.01)';
      OUTPUT_LOAD='(1.0,-1.0)';
    'IO92':
      PIN_NUMBER='(92)';
      BIDIRECTIONAL='TRUE';
      INPUT_LOAD='(-0.01,0.01)';
      OUTPUT_LOAD='(1.0,-1.0)';
    'IO93':
      PIN_NUMBER='(93)';
      BIDIRECTIONAL='TRUE';
      INPUT_LOAD='(-0.01,0.01)';
      OUTPUT_LOAD='(1.0,-1.0)';
    'IO94':
      PIN_NUMBER='(94)';
      BIDIRECTIONAL='TRUE';
      INPUT_LOAD='(-0.01,0.01)';
      OUTPUT_LOAD='(1.0,-1.0)';
    'IO95':
      PIN_NUMBER='(95)';
      BIDIRECTIONAL='TRUE';
      INPUT_LOAD='(-0.01,0.01)';
      OUTPUT_LOAD='(1.0,-1.0)';
    'IO96':
      PIN_NUMBER='(96)';
      BIDIRECTIONAL='TRUE';
      INPUT_LOAD='(-0.01,0.01)';
      OUTPUT_LOAD='(1.0,-1.0)';
    'IO97':
      PIN_NUMBER='(97)';
      BIDIRECTIONAL='TRUE';
      INPUT_LOAD='(-0.01,0.01)';
      OUTPUT_LOAD='(1.0,-1.0)';
    'IO98':
      PIN_NUMBER='(98)';
      BIDIRECTIONAL='TRUE';
      INPUT_LOAD='(-0.01,0.01)';
      OUTPUT_LOAD='(1.0,-1.0)';
    'IO99':
      PIN_NUMBER='(99)';
      BIDIRECTIONAL='TRUE';
      INPUT_LOAD='(-0.01,0.01)';
      OUTPUT_LOAD='(1.0,-1.0)';
  end_pin;
  body
    PART_NAME='SCONN120_A28699018';
    PHYS_DES_PREFIX='J';
  end_body;
end_primitive;

END.
